# T6G (Grand Teton) — schematic netlist excerpt (pin names and nets, part order shuffled) for the footprints in the layout excerpt that follows; sources: Cadence DE-HDL packaged netlist, KiCad conversion of 04192023_DAF0TMB3IC0_F0TG_MB_C_brd_V02_OCP.brd

C1827  Q_CAP  0.1UF 25V 10% X7R  pkg 0402  page 138 : A = P3V3_AUX ; B = GND
C6612  Q_CAP_DIFFBUS  DIFF BUS_0.22UF 6.3V 20% X6S  pkg C0201  page 308 : \1\ = P5E_CPU0_P3_TX_BUF_C_DN<7> ; \2\ = P5E_CPU0_P3_TX_BUF_DN<7>
C2216  Q_CAP  22UF 4V 20% X6S  pkg C0402  page 69 : A = PVDDCR_CPU1_P0 ; B = GND

(kicad_pcb
	(version 20260206)
	(generator "pcbnew")
	(generator_version "10.0")
	(general
		(thickness 1.6)
		(legacy_teardrops no)
	)
	(paper "A4")
	(title_block
		(title "04192023_DAF0TMB3IC0_F0TG_MB_C_brd_V02_OCP.brd")
		(comment 1 "Grand Teton / footprints 5465-5467 of 8354")
	)
	(layers
		(0 "F.Cu" signal "TOP")
		(4 "In1.Cu" signal "GND")
		(6 "In2.Cu" signal "IN1")
		(8 "In3.Cu" signal "GND1")
		(10 "In4.Cu" signal "IN2")
		(12 "In5.Cu" signal "GND2")
		(14 "In6.Cu" signal "IN3")
		(16 "In7.Cu" signal "GND3")
		(18 "In8.Cu" signal "VCC")
		(20 "In9.Cu" signal "VCC1")
		(22 "In10.Cu" signal "GND4")
		(24 "In11.Cu" signal "IN4")
		(26 "In12.Cu" signal "GND5")
		(28 "In13.Cu" signal "IN5")
		(30 "In14.Cu" signal "GND6")
		(32 "In15.Cu" signal "IN6")
		(34 "In16.Cu" signal "GND7")
		(2 "B.Cu" signal "BOTTOM")
		(9 "F.Adhes" user "F.Adhesive")
		(11 "B.Adhes" user "B.Adhesive")
		(13 "F.Paste" user "Package Geometry/Pastemask Top")
		(15 "B.Paste" user "Package Geometry/Pastemask Bottom")
		(5 "F.SilkS" user "Ref Des/Silkscreen Top")
		(7 "B.SilkS" user "Ref Des/Silkscreen Bottom")
		(1 "F.Mask" user "Board Geometry/Soldermask Top")
		(3 "B.Mask" user "Board Geometry/Soldermask Bottom")
		(17 "Dwgs.User" user "User.Drawings")
		(19 "Cmts.User" user "User.Comments")
		(21 "Eco1.User" user "User.Eco1")
		(23 "Eco2.User" user "User.Eco2")
		(25 "Edge.Cuts" user "Board Geometry/Outline")
		(27 "Margin" user)
		(31 "F.CrtYd" user "Package Geometry/Place Bound Top")
		(29 "B.CrtYd" user "Package Geometry/Place Bound Bottom")
		(35 "F.Fab" user "Ref Des/Assembly Top")
		(33 "B.Fab" user "Ref Des/Assembly Bottom")
	)
	(footprint ""
		(layer "B.Cu")
		(at 353.517454 -269.30731)
		(property "Reference" "C2216"
			(at 0 0 0)
			(layer "B.SilkS")
			(hide yes)
			(effects
				(font
					(size 1.27 1.27)
				)
				(justify mirror)
			)
		)
		(property "Value" ""
			(at 0 0 0)
			(layer "B.Fab")
			(effects
				(font
					(size 1.27 1.27)
				)
				(justify mirror)
			)
		)
		(duplicate_pad_numbers_are_jumpers no)
		(fp_line
			(start -0.7874 -0.4064)
			(end -0.7874 0.4064)
			(stroke
				(width 0.1524)
				(type default)
			)
			(layer "B.SilkS")
		)
		(fp_line
			(start -0.7874 0.4064)
			(end 0.7874 0.4064)
			(stroke
				(width 0.1524)
				(type default)
			)
			(layer "B.SilkS")
		)
		(fp_line
			(start 0.7874 -0.4064)
			(end -0.7874 -0.4064)
			(stroke
				(width 0.1524)
				(type default)
			)
			(layer "B.SilkS")
		)
		(fp_line
			(start 0.7874 0.4064)
			(end 0.7874 -0.4064)
			(stroke
				(width 0.1524)
				(type default)
			)
			(layer "B.SilkS")
		)
		(fp_line
			(start -0.67945 -0.3048)
			(end -0.67945 0.3048)
			(stroke
				(width 0.1)
				(type default)
			)
			(layer "B.Fab")
		)
		(fp_line
			(start -0.67945 0.3048)
			(end -0.120396 0.3048)
			(stroke
				(width 0.1)
				(type default)
			)
			(layer "B.Fab")
		)
		(fp_line
			(start -0.12065 -0.3048)
			(end -0.67945 -0.3048)
			(stroke
				(width 0.1)
				(type default)
			)
			(layer "B.Fab")
		)
		(fp_line
			(start -0.12065 -0.2794)
			(end -0.12065 -0.3048)
			(stroke
				(width 0.1)
				(type default)
			)
			(layer "B.Fab")
		)
		(fp_line
			(start -0.120396 0.2794)
			(end 0.12065 0.2794)
			(stroke
				(width 0.1)
				(type default)
			)
			(layer "B.Fab")
		)
		(fp_line
			(start -0.120396 0.3048)
			(end -0.120396 0.2794)
			(stroke
				(width 0.1)
				(type default)
			)
			(layer "B.Fab")
		)
		(fp_line
			(start 0.12065 -0.305054)
			(end 0.12065 -0.2794)
			(stroke
				(width 0.1)
				(type default)
			)
			(layer "B.Fab")
		)
		(fp_line
			(start 0.12065 -0.2794)
			(end -0.12065 -0.2794)
			(stroke
				(width 0.1)
				(type default)
			)
			(layer "B.Fab")
		)
		(fp_line
			(start 0.12065 0.2794)
			(end 0.12065 0.3048)
			(stroke
				(width 0.1)
				(type default)
			)
			(layer "B.Fab")
		)
		(fp_line
			(start 0.12065 0.3048)
			(end 0.67945 0.3048)
			(stroke
				(width 0.1)
				(type default)
			)
			(layer "B.Fab")
		)
		(fp_line
			(start 0.67945 -0.305054)
			(end 0.12065 -0.305054)
			(stroke
				(width 0.1)
				(type default)
			)
			(layer "B.Fab")
		)
		(fp_line
			(start 0.67945 0.3048)
			(end 0.67945 -0.305054)
			(stroke
				(width 0.1)
				(type default)
			)
			(layer "B.Fab")
		)
		(pad "1" smd circle
			(at 0.40005 0 180)
			(size 0 0)
			(layers "B.Cu" "B.Mask" "B.Paste")
			(net "PVDDCR_CPU1_P0")
		)
		(pad "2" smd circle
			(at -0.40005 0 180)
			(size 0 0)
			(layers "B.Cu" "B.Mask" "B.Paste")
			(net "GND")
		)
	)
	(footprint ""
		(layer "B.Cu")
		(at 192.795906 -72.804528)
		(property "Reference" "C1827"
			(at 0 0 0)
			(layer "B.SilkS")
			(hide yes)
			(effects
				(font
					(size 1.27 1.27)
				)
				(justify mirror)
			)
		)
		(property "Value" ""
			(at 0 0 0)
			(layer "B.Fab")
			(effects
				(font
					(size 1.27 1.27)
				)
				(justify mirror)
			)
		)
		(duplicate_pad_numbers_are_jumpers no)
		(fp_line
			(start -0.7874 -0.4064)
			(end -0.7874 0.4064)
			(stroke
				(width 0.1524)
				(type default)
			)
			(layer "B.SilkS")
		)
		(fp_line
			(start -0.7874 0.4064)
			(end 0.7874 0.4064)
			(stroke
				(width 0.1524)
				(type default)
			)
			(layer "B.SilkS")
		)
		(fp_line
			(start 0.7874 -0.4064)
			(end -0.7874 -0.4064)
			(stroke
				(width 0.1524)
				(type default)
			)
			(layer "B.SilkS")
		)
		(fp_line
			(start 0.7874 0.4064)
			(end 0.7874 -0.4064)
			(stroke
				(width 0.1524)
				(type default)
			)
			(layer "B.SilkS")
		)
		(fp_line
			(start -0.67945 -0.3048)
			(end -0.67945 0.3048)
			(stroke
				(width 0.1)
				(type default)
			)
			(layer "B.Fab")
		)
		(fp_line
			(start -0.67945 0.3048)
			(end -0.120396 0.3048)
			(stroke
				(width 0.1)
				(type default)
			)
			(layer "B.Fab")
		)
		(fp_line
			(start -0.12065 -0.3048)
			(end -0.67945 -0.3048)
			(stroke
				(width 0.1)
				(type default)
			)
			(layer "B.Fab")
		)
		(fp_line
			(start -0.12065 -0.2794)
			(end -0.12065 -0.3048)
			(stroke
				(width 0.1)
				(type default)
			)
			(layer "B.Fab")
		)
		(fp_line
			(start -0.120396 0.2794)
			(end 0.12065 0.2794)
			(stroke
				(width 0.1)
				(type default)
			)
			(layer "B.Fab")
		)
		(fp_line
			(start -0.120396 0.3048)
			(end -0.120396 0.2794)
			(stroke
				(width 0.1)
				(type default)
			)
			(layer "B.Fab")
		)
		(fp_line
			(start 0.12065 -0.305054)
			(end 0.12065 -0.2794)
			(stroke
				(width 0.1)
				(type default)
			)
			(layer "B.Fab")
		)
		(fp_line
			(start 0.12065 -0.2794)
			(end -0.12065 -0.2794)
			(stroke
				(width 0.1)
				(type default)
			)
			(layer "B.Fab")
		)
		(fp_line
			(start 0.12065 0.2794)
			(end 0.12065 0.3048)
			(stroke
				(width 0.1)
				(type default)
			)
			(layer "B.Fab")
		)
		(fp_line
			(start 0.12065 0.3048)
			(end 0.67945 0.3048)
			(stroke
				(width 0.1)
				(type default)
			)
			(layer "B.Fab")
		)
		(fp_line
			(start 0.67945 -0.305054)
			(end 0.12065 -0.305054)
			(stroke
				(width 0.1)
				(type default)
			)
			(layer "B.Fab")
		)
		(fp_line
			(start 0.67945 0.3048)
			(end 0.67945 -0.305054)
			(stroke
				(width 0.1)
				(type default)
			)
			(layer "B.Fab")
		)
		(pad "1" smd circle
			(at 0.40005 0 180)
			(size 0 0)
			(layers "B.Cu" "B.Mask" "B.Paste")
			(net "P3V3_AUX")
		)
		(pad "2" smd circle
			(at -0.40005 0 180)
			(size 0 0)
			(layers "B.Cu" "B.Mask" "B.Paste")
			(net "GND")
		)
	)
	(footprint ""
		(layer "B.Cu")
		(at 393.843002 -416.899344 90)
		(property "Reference" "C6612"
			(at 0 0 90)
			(layer "B.SilkS")
			(hide yes)
			(effects
				(font
					(size 1.27 1.27)
				)
				(justify mirror)
			)
		)
		(property "Value" ""
			(at 0 0 90)
			(layer "B.Fab")
			(effects
				(font
					(size 1.27 1.27)
				)
				(justify mirror)
			)
		)
		(duplicate_pad_numbers_are_jumpers no)
		(fp_line
			(start 0.299974 -0.150114)
			(end -0.299974 -0.150114)
			(stroke
				(width 0.1)
				(type default)
			)
			(layer "B.Fab")
		)
		(fp_line
			(start -0.299974 -0.150114)
			(end -0.299974 0.150114)
			(stroke
				(width 0.1)
				(type default)
			)
			(layer "B.Fab")
		)
		(fp_line
			(start 0.299974 0.150114)
			(end 0.299974 -0.150114)
			(stroke
				(width 0.1)
				(type default)
			)
			(layer "B.Fab")
		)
		(fp_line
			(start -0.299974 0.150114)
			(end 0.299974 0.150114)
			(stroke
				(width 0.1)
				(type default)
			)
			(layer "B.Fab")
		)
		(pad "1" smd rect
			(at 0.2667 0 270)
			(size 0.3048 0.381)
			(layers "B.Cu" "B.Mask" "B.Paste")
			(net "P5E_CPU0_P3_TX_BUF_C_DN<7>")
		)
		(pad "2" smd rect
			(at -0.2667 0 270)
			(size 0.3048 0.381)
			(layers "B.Cu" "B.Mask" "B.Paste")
			(net "P5E_CPU0_P3_TX_BUF_DN<7>")
		)
	)
)
